(kicad_pcb
	(version 20240108)
	(generator "pcbnew")
	(generator_version "8.0")
	(general
		(thickness 1.62)
		(legacy_teardrops no)
	)
	(paper "A4")
	(title_block
		(title "Jetson Orin Baseboard")
		(date "2025-03-12")
		(rev "1.3.4")
		(company "Antmicro Ltd")
		(comment 1 "www.antmicro.com")
		(comment 9 "footprints 471-475 of 677")
	)
	(layers
		(0 "F.Cu" signal)
		(1 "In1.Cu" signal)
		(2 "In2.Cu" signal)
		(3 "In3.Cu" signal)
		(4 "In4.Cu" jumper)
		(5 "In5.Cu" signal)
		(6 "In6.Cu" signal)
		(31 "B.Cu" signal)
		(32 "B.Adhes" user "B.Adhesive")
		(33 "F.Adhes" user "F.Adhesive")
		(34 "B.Paste" user)
		(35 "F.Paste" user)
		(36 "B.SilkS" user "B.Silkscreen")
		(37 "F.SilkS" user "F.Silkscreen")
		(38 "B.Mask" user)
		(39 "F.Mask" user)
		(40 "Dwgs.User" user "User.Drawings")
		(41 "Cmts.User" user "User.Comments")
		(42 "Eco1.User" user "User.Eco1")
		(43 "Eco2.User" user "User.Eco2")
		(44 "Edge.Cuts" user)
		(45 "Margin" user)
		(46 "B.CrtYd" user "B.Courtyard")
		(47 "F.CrtYd" user "F.Courtyard")
		(48 "B.Fab" user)
		(49 "F.Fab" user)
	)
	(footprint "antmicro-footprints:C_0402_1005Metric"
		(layer "B.Cu")
		(at 95.55 91.925)
		(descr "Capacitor SMD 0402")
		(tags "capacitor SMD 0402")
		(property "Reference" "C87"
			(at 5.01 0.065 180)
			(layer "B.SilkS")
			(effects
				(font
					(size 0.7 0.7)
					(thickness 0.15)
				)
				(justify left bottom mirror)
			)
		)
		(property "Value" "C_100n_0402"
			(at 0 -1.4 180)
			(layer "B.Fab")
			(effects
				(font
					(size 0.7 0.7)
					(thickness 0.15)
				)
				(justify left bottom mirror)
			)
		)
		(property "Footprint" "antmicro-footprints:C_0402_1005Metric"
			(at 0 0 0)
			(layer "F.Fab")
			(hide yes)
			(effects
				(font
					(size 1.27 1.27)
					(thickness 0.15)
				)
			)
		)
		(property "Datasheet" "https://www.murata.com/products/productdetail?partno=GRM155R61H104KE14%23"
			(at 0 0 0)
			(layer "F.Fab")
			(hide yes)
			(effects
				(font
					(size 1.27 1.27)
					(thickness 0.15)
				)
			)
		)
		(property "Author" "Antmicro"
			(at 0 0 0)
			(layer "B.Fab")
			(hide yes)
			(effects
				(font
					(size 1 1)
					(thickness 0.15)
				)
				(justify mirror)
			)
		)
		(property "Dielectric" "X5R"
			(at 0 0 0)
			(layer "B.Fab")
			(hide yes)
			(effects
				(font
					(size 1 1)
					(thickness 0.15)
				)
				(justify mirror)
			)
		)
		(property "License" "Apache-2.0"
			(at 0 0 0)
			(layer "B.Fab")
			(hide yes)
			(effects
				(font
					(size 1 1)
					(thickness 0.15)
				)
				(justify mirror)
			)
		)
		(property "MPN" "GRM155R61H104KE14D"
			(at 0 0 0)
			(layer "B.Fab")
			(hide yes)
			(effects
				(font
					(size 1 1)
					(thickness 0.15)
				)
				(justify mirror)
			)
		)
		(property "Manufacturer" "Murata"
			(at 0 0 0)
			(layer "B.Fab")
			(hide yes)
			(effects
				(font
					(size 1 1)
					(thickness 0.15)
				)
				(justify mirror)
			)
		)
		(property "Val" "100n"
			(at 0 0 0)
			(layer "B.Fab")
			(hide yes)
			(effects
				(font
					(size 1 1)
					(thickness 0.15)
				)
				(justify mirror)
			)
		)
		(property "Voltage" "50V"
			(at 0 0 0)
			(layer "B.Fab")
			(hide yes)
			(effects
				(font
					(size 1 1)
					(thickness 0.15)
				)
				(justify mirror)
			)
		)
		(sheetname "HDMI")
		(sheetfile "hdmi.kicad_sch")
		(attr smd)
		(fp_rect
			(start -0.925 0.47)
			(end 0.925 -0.47)
			(stroke
				(width 0.05)
				(type default)
			)
			(fill none)
			(layer "B.CrtYd")
		)
		(fp_line
			(start -0.494 -0.248)
			(end 0.504 -0.248)
			(stroke
				(width 0.15)
				(type solid)
			)
			(layer "B.Fab")
		)
		(fp_line
			(start -0.494 0.25)
			(end -0.494 -0.248)
			(stroke
				(width 0.15)
				(type solid)
			)
			(layer "B.Fab")
		)
		(fp_line
			(start 0.504 -0.248)
			(end 0.504 0.25)
			(stroke
				(width 0.15)
				(type solid)
			)
			(layer "B.Fab")
		)
		(fp_line
			(start 0.504 0.25)
			(end -0.494 0.25)
			(stroke
				(width 0.15)
				(type solid)
			)
			(layer "B.Fab")
		)
		(fp_text user "Author: Antmicro"
			(at -0.932 -4.17 180)
			(layer "B.Fab")
			(hide yes)
			(effects
				(font
					(size 0.7 0.7)
					(thickness 0.15)
				)
				(justify left bottom mirror)
			)
		)
		(fp_text user "License: Apache-2.0"
			(at -0.932 -5.17 180)
			(layer "B.Fab")
			(hide yes)
			(effects
				(font
					(size 0.7 0.7)
					(thickness 0.15)
				)
				(justify left bottom mirror)
			)
		)
		(fp_text user "${REFERENCE}"
			(at -0.932 -3.168 180)
			(layer "B.Fab")
			(hide yes)
			(effects
				(font
					(size 0.7 0.7)
					(thickness 0.15)
				)
				(justify left bottom mirror)
			)
		)
		(pad "1" smd roundrect
			(at -0.48 0)
			(size 0.59 0.64)
			(layers "B.Cu" "B.Paste" "B.Mask")
			(roundrect_rratio 0.25)
			(net 663 "/HDMI/DP_MUX_D1-")
			(pintype "passive")
		)
		(pad "2" smd roundrect
			(at 0.48 0)
			(size 0.59 0.64)
			(layers "B.Cu" "B.Paste" "B.Mask")
			(roundrect_rratio 0.25)
			(net 418 "DP1_TXD2_HDMI_TX0_N")
			(pintype "passive")
		)
	)
	(footprint "antmicro-footprints:R_0402_1005Metric"
		(layer "B.Cu")
		(at 75 103.4 90)
		(descr "Resistor SMD 0402")
		(tags "resistor SMD 0402")
		(property "Reference" "R91"
			(at 5.16 1.67 -90)
			(layer "B.SilkS")
			(effects
				(font
					(size 0.7 0.7)
					(thickness 0.15)
				)
				(justify left bottom mirror)
			)
		)
		(property "Value" "R_1k_0402"
			(at 0 -1.4 -90)
			(layer "B.Fab")
			(effects
				(font
					(size 0.7 0.7)
					(thickness 0.15)
				)
				(justify left bottom mirror)
			)
		)
		(property "Footprint" "antmicro-footprints:R_0402_1005Metric"
			(at 0 0 90)
			(layer "F.Fab")
			(hide yes)
			(effects
				(font
					(size 1.27 1.27)
					(thickness 0.15)
				)
			)
		)
		(property "Datasheet" "https://www.bourns.com/docs/product-datasheets/cr.pdf"
			(at 0 0 90)
			(layer "F.Fab")
			(hide yes)
			(effects
				(font
					(size 1.27 1.27)
					(thickness 0.15)
				)
			)
		)
		(property "Author" "Antmicro"
			(at 178.4 28.4 0)
			(layer "B.Fab")
			(hide yes)
			(effects
				(font
					(size 1 1)
					(thickness 0.15)
				)
				(justify mirror)
			)
		)
		(property "License" "Apache-2.0"
			(at 178.4 28.4 0)
			(layer "B.Fab")
			(hide yes)
			(effects
				(font
					(size 1 1)
					(thickness 0.15)
				)
				(justify mirror)
			)
		)
		(property "MPN" "CR0402-FX-1001GLF"
			(at 178.4 28.4 0)
			(layer "B.Fab")
			(hide yes)
			(effects
				(font
					(size 1 1)
					(thickness 0.15)
				)
				(justify mirror)
			)
		)
		(property "Manufacturer" "Bourns"
			(at 178.4 28.4 0)
			(layer "B.Fab")
			(hide yes)
			(effects
				(font
					(size 1 1)
					(thickness 0.15)
				)
				(justify mirror)
			)
		)
		(property "Tolerance" "1%"
			(at 178.4 28.4 0)
			(layer "B.Fab")
			(hide yes)
			(effects
				(font
					(size 1 1)
					(thickness 0.15)
				)
				(justify mirror)
			)
		)
		(property "Val" "1k"
			(at 178.4 28.4 0)
			(layer "B.Fab")
			(hide yes)
			(effects
				(font
					(size 1 1)
					(thickness 0.15)
				)
				(justify mirror)
			)
		)
		(sheetname "USB Debug, DP")
		(sheetfile "usb.kicad_sch")
		(attr smd exclude_from_pos_files exclude_from_bom dnp)
		(fp_rect
			(start -0.925 0.47)
			(end 0.925 -0.47)
			(stroke
				(width 0.05)
				(type default)
			)
			(fill none)
			(layer "B.CrtYd")
		)
		(fp_rect
			(start -0.5 0.25)
			(end 0.5 -0.25)
			(stroke
				(width 0.15)
				(type solid)
			)
			(fill none)
			(layer "B.Fab")
		)
		(fp_text user "${REFERENCE}"
			(at -0.95 -3.168 -90)
			(layer "B.Fab")
			(hide yes)
			(effects
				(font
					(size 0.7 0.7)
					(thickness 0.15)
				)
				(justify left bottom mirror)
			)
		)
		(fp_text user "Author: Antmicro"
			(at -0.95 -4.169 -90)
			(layer "B.Fab")
			(hide yes)
			(effects
				(font
					(size 0.7 0.7)
					(thickness 0.15)
				)
				(justify left bottom mirror)
			)
		)
		(fp_text user "License: Apache-2.0"
			(at -0.95 -5.169 -90)
			(layer "B.Fab")
			(hide yes)
			(effects
				(font
					(size 0.7 0.7)
					(thickness 0.15)
				)
				(justify left bottom mirror)
			)
		)
		(pad "1" smd roundrect
			(at -0.48 0 90)
			(size 0.59 0.64)
			(layers "B.Cu" "B.Paste" "B.Mask")
			(roundrect_rratio 0.25)
			(net 307 "/USB Debug, DP/USBC0_DPEQ0")
			(pintype "passive")
		)
		(pad "2" smd roundrect
			(at 0.48 0 90)
			(size 0.59 0.64)
			(layers "B.Cu" "B.Paste" "B.Mask")
			(roundrect_rratio 0.25)
			(net 87 "+3V3")
			(pintype "passive")
		)
	)
	(footprint "antmicro-footprints:R_0402_1005Metric"
		(layer "B.Cu")
		(at 91.3 116.1 -90)
		(descr "Resistor SMD 0402")
		(tags "resistor SMD 0402")
		(property "Reference" "R280"
			(at -2.55 -4.8 90)
			(layer "B.SilkS")
			(effects
				(font
					(size 0.7 0.7)
					(thickness 0.15)
				)
				(justify left bottom mirror)
			)
		)
		(property "Value" "R_2k2_0402"
			(at 0 -1.4 90)
			(layer "B.Fab")
			(effects
				(font
					(size 0.7 0.7)
					(thickness 0.15)
				)
				(justify left bottom mirror)
			)
		)
		(property "Footprint" "antmicro-footprints:R_0402_1005Metric"
			(at 0 0 -90)
			(layer "F.Fab")
			(hide yes)
			(effects
				(font
					(size 1.27 1.27)
					(thickness 0.15)
				)
			)
		)
		(property "Datasheet" "https://www.bourns.com/docs/product-datasheets/cr.pdf"
			(at 0 0 -90)
			(layer "F.Fab")
			(hide yes)
			(effects
				(font
					(size 1.27 1.27)
					(thickness 0.15)
				)
			)
		)
		(property "Author" "Antmicro"
			(at -24.8 207.4 0)
			(layer "B.Fab")
			(hide yes)
			(effects
				(font
					(size 1 1)
					(thickness 0.15)
				)
				(justify mirror)
			)
		)
		(property "License" "Apache-2.0"
			(at -24.8 207.4 0)
			(layer "B.Fab")
			(hide yes)
			(effects
				(font
					(size 1 1)
					(thickness 0.15)
				)
				(justify mirror)
			)
		)
		(property "MPN" "CR0402-FX-2201GLF"
			(at -24.8 207.4 0)
			(layer "B.Fab")
			(hide yes)
			(effects
				(font
					(size 1 1)
					(thickness 0.15)
				)
				(justify mirror)
			)
		)
		(property "Manufacturer" "Bourns"
			(at -24.8 207.4 0)
			(layer "B.Fab")
			(hide yes)
			(effects
				(font
					(size 1 1)
					(thickness 0.15)
				)
				(justify mirror)
			)
		)
		(property "Tolerance" "1%"
			(at -24.8 207.4 0)
			(layer "B.Fab")
			(hide yes)
			(effects
				(font
					(size 1 1)
					(thickness 0.15)
				)
				(justify mirror)
			)
		)
		(property "Val" "2k2"
			(at -24.8 207.4 0)
			(layer "B.Fab")
			(hide yes)
			(effects
				(font
					(size 1 1)
					(thickness 0.15)
				)
				(justify mirror)
			)
		)
		(sheetname "HDMI")
		(sheetfile "hdmi.kicad_sch")
		(attr smd exclude_from_pos_files exclude_from_bom dnp)
		(fp_rect
			(start -0.925 0.47)
			(end 0.925 -0.47)
			(stroke
				(width 0.05)
				(type default)
			)
			(fill none)
			(layer "B.CrtYd")
		)
		(fp_rect
			(start -0.5 0.25)
			(end 0.5 -0.25)
			(stroke
				(width 0.15)
				(type solid)
			)
			(fill none)
			(layer "B.Fab")
		)
		(fp_text user "Author: Antmicro"
			(at -0.95 -4.169 90)
			(layer "B.Fab")
			(hide yes)
			(effects
				(font
					(size 0.7 0.7)
					(thickness 0.15)
				)
				(justify left bottom mirror)
			)
		)
		(fp_text user "License: Apache-2.0"
			(at -0.95 -5.169 90)
			(layer "B.Fab")
			(hide yes)
			(effects
				(font
					(size 0.7 0.7)
					(thickness 0.15)
				)
				(justify left bottom mirror)
			)
		)
		(fp_text user "${REFERENCE}"
			(at -0.95 -3.168 90)
			(layer "B.Fab")
			(hide yes)
			(effects
				(font
					(size 0.7 0.7)
					(thickness 0.15)
				)
				(justify left bottom mirror)
			)
		)
		(pad "1" smd roundrect
			(at -0.48 0 270)
			(size 0.59 0.64)
			(layers "B.Cu" "B.Paste" "B.Mask")
			(roundrect_rratio 0.25)
			(net 555 "/HDMI/HDMI_SCL_3V3")
			(pintype "passive")
		)
		(pad "2" smd roundrect
			(at 0.48 0 270)
			(size 0.59 0.64)
			(layers "B.Cu" "B.Paste" "B.Mask")
			(roundrect_rratio 0.25)
			(net 87 "+3V3")
			(pintype "passive")
		)
	)
	(footprint "antmicro-footprints:R_0402_1005Metric"
		(layer "B.Cu")
		(at 76 108.3 90)
		(descr "Resistor SMD 0402")
		(tags "resistor SMD 0402")
		(property "Reference" "R96"
			(at -0.63 2.37 -90)
			(layer "B.SilkS")
			(effects
				(font
					(size 0.7 0.7)
					(thickness 0.15)
				)
				(justify left bottom mirror)
			)
		)
		(property "Value" "R_1k_0402"
			(at 0 -1.4 -90)
			(layer "B.Fab")
			(effects
				(font
					(size 0.7 0.7)
					(thickness 0.15)
				)
				(justify left bottom mirror)
			)
		)
		(property "Footprint" "antmicro-footprints:R_0402_1005Metric"
			(at 0 0 90)
			(layer "F.Fab")
			(hide yes)
			(effects
				(font
					(size 1.27 1.27)
					(thickness 0.15)
				)
			)
		)
		(property "Datasheet" "https://www.bourns.com/docs/product-datasheets/cr.pdf"
			(at 0 0 90)
			(layer "F.Fab")
			(hide yes)
			(effects
				(font
					(size 1.27 1.27)
					(thickness 0.15)
				)
			)
		)
		(property "Author" "Antmicro"
			(at 184.3 32.3 0)
			(layer "B.Fab")
			(hide yes)
			(effects
				(font
					(size 1 1)
					(thickness 0.15)
				)
				(justify mirror)
			)
		)
		(property "License" "Apache-2.0"
			(at 184.3 32.3 0)
			(layer "B.Fab")
			(hide yes)
			(effects
				(font
					(size 1 1)
					(thickness 0.15)
				)
				(justify mirror)
			)
		)
		(property "MPN" "CR0402-FX-1001GLF"
			(at 184.3 32.3 0)
			(layer "B.Fab")
			(hide yes)
			(effects
				(font
					(size 1 1)
					(thickness 0.15)
				)
				(justify mirror)
			)
		)
		(property "Manufacturer" "Bourns"
			(at 184.3 32.3 0)
			(layer "B.Fab")
			(hide yes)
			(effects
				(font
					(size 1 1)
					(thickness 0.15)
				)
				(justify mirror)
			)
		)
		(property "Tolerance" "1%"
			(at 184.3 32.3 0)
			(layer "B.Fab")
			(hide yes)
			(effects
				(font
					(size 1 1)
					(thickness 0.15)
				)
				(justify mirror)
			)
		)
		(property "Val" "1k"
			(at 184.3 32.3 0)
			(layer "B.Fab")
			(hide yes)
			(effects
				(font
					(size 1 1)
					(thickness 0.15)
				)
				(justify mirror)
			)
		)
		(sheetname "USB Debug, DP")
		(sheetfile "usb.kicad_sch")
		(attr smd exclude_from_pos_files exclude_from_bom dnp)
		(fp_rect
			(start -0.925 0.47)
			(end 0.925 -0.47)
			(stroke
				(width 0.05)
				(type default)
			)
			(fill none)
			(layer "B.CrtYd")
		)
		(fp_rect
			(start -0.5 0.25)
			(end 0.5 -0.25)
			(stroke
				(width 0.15)
				(type solid)
			)
			(fill none)
			(layer "B.Fab")
		)
		(fp_text user "${REFERENCE}"
			(at -0.95 -3.168 -90)
			(layer "B.Fab")
			(hide yes)
			(effects
				(font
					(size 0.7 0.7)
					(thickness 0.15)
				)
				(justify left bottom mirror)
			)
		)
		(fp_text user "Author: Antmicro"
			(at -0.95 -4.169 -90)
			(layer "B.Fab")
			(hide yes)
			(effects
				(font
					(size 0.7 0.7)
					(thickness 0.15)
				)
				(justify left bottom mirror)
			)
		)
		(fp_text user "License: Apache-2.0"
			(at -0.95 -5.169 -90)
			(layer "B.Fab")
			(hide yes)
			(effects
				(font
					(size 0.7 0.7)
					(thickness 0.15)
				)
				(justify left bottom mirror)
			)
		)
		(pad "1" smd roundrect
			(at -0.48 0 90)
			(size 0.59 0.64)
			(layers "B.Cu" "B.Paste" "B.Mask")
			(roundrect_rratio 0.25)
			(net 309 "/USB Debug, DP/USBC0_EQ0")
			(pintype "passive")
		)
		(pad "2" smd roundrect
			(at 0.48 0 90)
			(size 0.59 0.64)
			(layers "B.Cu" "B.Paste" "B.Mask")
			(roundrect_rratio 0.25)
			(net 1 "GND")
			(pintype "passive")
		)
	)
	(footprint "antmicro-footprints:SOD-523"
		(layer "B.Cu")
		(at 58.95 77.35)
		(property "Reference" "D36"
			(at 20.77 9.01 0)
			(layer "B.SilkS")
			(effects
				(font
					(size 0.7 0.7)
					(thickness 0.15)
				)
				(justify right bottom mirror)
			)
		)
		(property "Value" "RB521S30T1G"
			(at 0 -1.499 0)
			(layer "B.Fab")
			(effects
				(font
					(size 0.7 0.7)
					(thickness 0.15)
				)
				(justify right bottom mirror)
			)
		)
		(property "Footprint" "antmicro-footprints:SOD-523"
			(at 0 0 0)
			(layer "F.Fab")
			(hide yes)
			(effects
				(font
					(size 1.27 1.27)
					(thickness 0.15)
				)
			)
		)
		(property "Datasheet" "https://www.onsemi.com/pdf/datasheet/rb521s30t1-d.pdf"
			(at 0 0 0)
			(layer "F.Fab")
			(hide yes)
			(effects
				(font
					(size 1.27 1.27)
					(thickness 0.15)
				)
			)
		)
		(property "Author" "Antmicro"
			(at 0 0 0)
			(layer "B.Fab")
			(hide yes)
			(effects
				(font
					(size 1 1)
					(thickness 0.15)
				)
				(justify mirror)
			)
		)
		(property "License" "Apache-2.0"
			(at 0 0 0)
			(layer "B.Fab")
			(hide yes)
			(effects
				(font
					(size 1 1)
					(thickness 0.15)
				)
				(justify mirror)
			)
		)
		(property "MPN" "RB521S30T1G"
			(at 0 0 0)
			(layer "B.Fab")
			(hide yes)
			(effects
				(font
					(size 1 1)
					(thickness 0.15)
				)
				(justify mirror)
			)
		)
		(property "Manufacturer" "ON Semiconductor"
			(at 0 0 0)
			(layer "B.Fab")
			(hide yes)
			(effects
				(font
					(size 1 1)
					(thickness 0.15)
				)
				(justify mirror)
			)
		)
		(sheetname "Supply")
		(sheetfile "supply.kicad_sch")
		(attr smd)
		(fp_line
			(start -0.35 -0.5)
			(end -0.35 0.5)
			(stroke
				(width 0.15)
				(type solid)
			)
			(layer "B.SilkS")
		)
		(fp_rect
			(start -1 0.6)
			(end 1 -0.6)
			(stroke
				(width 0.05)
				(type solid)
			)
			(fill none)
			(layer "B.CrtYd")
		)
		(fp_line
			(start -0.652 0.425)
			(end -0.652 -0.423)
			(stroke
				(width 0.15)
				(type solid)
			)
			(layer "B.Fab")
		)
		(fp_line
			(start -0.35 -0.4)
			(end -0.35 0.4)
			(stroke
				(width 0.15)
				(type solid)
			)
			(layer "B.Fab")
		)
		(fp_line
			(start 0.65 -0.423)
			(end -0.652 -0.423)
			(stroke
				(width 0.15)
				(type solid)
			)
			(layer "B.Fab")
		)
		(fp_line
			(start 0.65 -0.423)
			(end 0.65 0.425)
			(stroke
				(width 0.15)
				(type solid)
			)
			(layer "B.Fab")
		)
		(fp_line
			(start 0.65 0.425)
			(end -0.652 0.425)
			(stroke
				(width 0.15)
				(type solid)
			)
			(layer "B.Fab")
		)
		(fp_text user "License: Apache-2.0"
			(at -1.276 -5.9 0)
			(layer "B.Fab")
			(hide yes)
			(effects
				(font
					(size 0.7 0.7)
					(thickness 0.15)
				)
				(justify right bottom mirror)
			)
		)
		(fp_text user "${REFERENCE}"
			(at -1.276 -3.499 0)
			(layer "B.Fab")
			(hide yes)
			(effects
				(font
					(size 0.7 0.7)
					(thickness 0.15)
				)
				(justify right bottom mirror)
			)
		)
		(fp_text user "Author: Antmicro"
			(at -1.276 -4.7 0)
			(layer "B.Fab")
			(hide yes)
			(effects
				(font
					(size 0.7 0.7)
					(thickness 0.15)
				)
				(justify right bottom mirror)
			)
		)
		(pad "1" smd roundrect
			(at -0.701 0)
			(size 0.5 0.6)
			(layers "B.Cu" "B.Paste" "B.Mask")
			(roundrect_rratio 0.25)
			(net 174 "Net-(D36-C)")
			(pinfunction "C")
			(pintype "passive")
		)
		(pad "2" smd roundrect
			(at 0.699 0)
			(size 0.5 0.6)
			(layers "B.Cu" "B.Paste" "B.Mask")
			(roundrect_rratio 0.25)
			(net 137 "Net-(D36-A)")
			(pinfunction "A")
			(pintype "passive")
		)
	)
)
